(kicad_pcb
	(version 20260206)
	(generator "pcbnew")
	(generator_version "10.0")
	(general
		(thickness 1.6)
		(legacy_teardrops no)
	)
	(paper "A4")
	(title_block
		(title "04192023_DAF0TMB3IC0_F0TG_MB_C_brd_V02_OCP.brd")
		(comment 1 "Grand Teton / footprints 1128-1134 of 8354")
	)
	(layers
		(0 "F.Cu" signal "TOP")
		(4 "In1.Cu" signal "GND")
		(6 "In2.Cu" signal "IN1")
		(8 "In3.Cu" signal "GND1")
		(10 "In4.Cu" signal "IN2")
		(12 "In5.Cu" signal "GND2")
		(14 "In6.Cu" signal "IN3")
		(16 "In7.Cu" signal "GND3")
		(18 "In8.Cu" signal "VCC")
		(20 "In9.Cu" signal "VCC1")
		(22 "In10.Cu" signal "GND4")
		(24 "In11.Cu" signal "IN4")
		(26 "In12.Cu" signal "GND5")
		(28 "In13.Cu" signal "IN5")
		(30 "In14.Cu" signal "GND6")
		(32 "In15.Cu" signal "IN6")
		(34 "In16.Cu" signal "GND7")
		(2 "B.Cu" signal "BOTTOM")
		(9 "F.Adhes" user "F.Adhesive")
		(11 "B.Adhes" user "B.Adhesive")
		(13 "F.Paste" user "Package Geometry/Pastemask Top")
		(15 "B.Paste" user "Package Geometry/Pastemask Bottom")
		(5 "F.SilkS" user "Ref Des/Silkscreen Top")
		(7 "B.SilkS" user "Ref Des/Silkscreen Bottom")
		(1 "F.Mask" user "Board Geometry/Soldermask Top")
		(3 "B.Mask" user "Board Geometry/Soldermask Bottom")
		(17 "Dwgs.User" user "User.Drawings")
		(19 "Cmts.User" user "User.Comments")
		(21 "Eco1.User" user "User.Eco1")
		(23 "Eco2.User" user "User.Eco2")
		(25 "Edge.Cuts" user "Board Geometry/Outline")
		(27 "Margin" user)
		(31 "F.CrtYd" user "Package Geometry/Place Bound Top")
		(29 "B.CrtYd" user "Package Geometry/Place Bound Bottom")
		(35 "F.Fab" user "Ref Des/Assembly Top")
		(33 "B.Fab" user "Ref Des/Assembly Bottom")
	)
	(footprint ""
		(layer "F.Cu")
		(at 63.084964 -408.517344 -90)
		(property "Reference" "C6640"
			(at 0 0 270)
			(layer "F.SilkS")
			(hide yes)
			(effects
				(font
					(size 1.27 1.27)
				)
			)
		)
		(property "Value" ""
			(at 0 0 270)
			(layer "F.Fab")
			(effects
				(font
					(size 1.27 1.27)
				)
			)
		)
		(duplicate_pad_numbers_are_jumpers no)
		(fp_line
			(start -0.299974 0.150114)
			(end -0.299974 -0.150114)
			(stroke
				(width 0.1)
				(type default)
			)
			(layer "F.Fab")
		)
		(fp_line
			(start 0.299974 0.150114)
			(end -0.299974 0.150114)
			(stroke
				(width 0.1)
				(type default)
			)
			(layer "F.Fab")
		)
		(fp_line
			(start -0.299974 -0.150114)
			(end 0.299974 -0.150114)
			(stroke
				(width 0.1)
				(type default)
			)
			(layer "F.Fab")
		)
		(fp_line
			(start 0.299974 -0.150114)
			(end 0.299974 0.150114)
			(stroke
				(width 0.1)
				(type default)
			)
			(layer "F.Fab")
		)
		(pad "1" smd rect
			(at -0.2667 0 270)
			(size 0.3048 0.381)
			(layers "F.Cu" "F.Mask" "F.Paste")
			(net "P5E_CPU1_P0_TX_BUF_C_DN<5>")
		)
		(pad "2" smd rect
			(at 0.2667 0 270)
			(size 0.3048 0.381)
			(layers "F.Cu" "F.Mask" "F.Paste")
			(net "P5E_CPU1_P0_TX_BUF_DN<5>")
		)
	)
	(footprint ""
		(layer "F.Cu")
		(at 212.993732 -117.748812 180)
		(property "Reference" "R133"
			(at 0 0 180)
			(layer "F.SilkS")
			(hide yes)
			(effects
				(font
					(size 1.27 1.27)
				)
			)
		)
		(property "Value" ""
			(at 0 0 180)
			(layer "F.Fab")
			(effects
				(font
					(size 1.27 1.27)
				)
			)
		)
		(duplicate_pad_numbers_are_jumpers no)
		(fp_line
			(start 0.7874 0.4064)
			(end -0.7874 0.4064)
			(stroke
				(width 0.1524)
				(type default)
			)
			(layer "F.SilkS")
		)
		(fp_line
			(start 0.7874 -0.4064)
			(end 0.7874 0.4064)
			(stroke
				(width 0.1524)
				(type default)
			)
			(layer "F.SilkS")
		)
		(fp_line
			(start -0.7874 0.4064)
			(end -0.7874 -0.4064)
			(stroke
				(width 0.1524)
				(type default)
			)
			(layer "F.SilkS")
		)
		(fp_line
			(start -0.7874 -0.4064)
			(end 0.7874 -0.4064)
			(stroke
				(width 0.1524)
				(type default)
			)
			(layer "F.SilkS")
		)
		(fp_line
			(start 0.67945 0.3048)
			(end 0.120396 0.3048)
			(stroke
				(width 0.1)
				(type default)
			)
			(layer "F.Fab")
		)
		(fp_line
			(start 0.67945 -0.3048)
			(end 0.67945 0.3048)
			(stroke
				(width 0.1)
				(type default)
			)
			(layer "F.Fab")
		)
		(fp_line
			(start 0.12065 -0.2794)
			(end 0.12065 -0.3048)
			(stroke
				(width 0.1)
				(type default)
			)
			(layer "F.Fab")
		)
		(fp_line
			(start 0.12065 -0.3048)
			(end 0.67945 -0.3048)
			(stroke
				(width 0.1)
				(type default)
			)
			(layer "F.Fab")
		)
		(fp_line
			(start 0.120396 0.3048)
			(end 0.120396 0.2794)
			(stroke
				(width 0.1)
				(type default)
			)
			(layer "F.Fab")
		)
		(fp_line
			(start 0.120396 0.2794)
			(end -0.12065 0.2794)
			(stroke
				(width 0.1)
				(type default)
			)
			(layer "F.Fab")
		)
		(fp_line
			(start -0.12065 0.3048)
			(end -0.67945 0.3048)
			(stroke
				(width 0.1)
				(type default)
			)
			(layer "F.Fab")
		)
		(fp_line
			(start -0.12065 0.2794)
			(end -0.12065 0.3048)
			(stroke
				(width 0.1)
				(type default)
			)
			(layer "F.Fab")
		)
		(fp_line
			(start -0.12065 -0.2794)
			(end 0.12065 -0.2794)
			(stroke
				(width 0.1)
				(type default)
			)
			(layer "F.Fab")
		)
		(fp_line
			(start -0.12065 -0.305054)
			(end -0.12065 -0.2794)
			(stroke
				(width 0.1)
				(type default)
			)
			(layer "F.Fab")
		)
		(fp_line
			(start -0.67945 0.3048)
			(end -0.67945 -0.305054)
			(stroke
				(width 0.1)
				(type default)
			)
			(layer "F.Fab")
		)
		(fp_line
			(start -0.67945 -0.305054)
			(end -0.12065 -0.305054)
			(stroke
				(width 0.1)
				(type default)
			)
			(layer "F.Fab")
		)
		(pad "1" smd circle
			(at -0.40005 0 180)
			(size 0 0)
			(layers "F.Cu" "F.Mask" "F.Paste")
			(net "FM_APML_MUX2_SEL")
		)
		(pad "2" smd circle
			(at 0.40005 0 180)
			(size 0 0)
			(layers "F.Cu" "F.Mask" "F.Paste")
			(net "FM_APML_MUX2_SEL_R")
		)
	)
	(footprint ""
		(layer "F.Cu")
		(at 438.827418 -332.63586 -90)
		(property "Reference" "PC801"
			(at -4.98094 -2.990596 90)
			(unlocked yes)
			(layer "F.SilkS")
			(effects
				(font
					(size 0.7874 0.5842)
					(thickness 0.1524)
				)
				(justify left)
			)
		)
		(property "Value" ""
			(at 0 0 270)
			(layer "F.Fab")
			(effects
				(font
					(size 1.27 1.27)
				)
			)
		)
		(duplicate_pad_numbers_are_jumpers no)
		(fp_line
			(start -1.988058 2.750058)
			(end 2.750058 2.750058)
			(stroke
				(width 0.1524)
				(type default)
			)
			(layer "F.SilkS")
		)
		(fp_line
			(start 2.750058 2.750058)
			(end 2.750058 0.9398)
			(stroke
				(width 0.1524)
				(type default)
			)
			(layer "F.SilkS")
		)
		(fp_line
			(start -2.750058 1.988058)
			(end -1.988058 2.750058)
			(stroke
				(width 0.1524)
				(type default)
			)
			(layer "F.SilkS")
		)
		(fp_line
			(start -2.750058 0.9398)
			(end -2.750058 1.988058)
			(stroke
				(width 0.1524)
				(type default)
			)
			(layer "F.SilkS")
		)
		(fp_line
			(start 2.750058 -0.9398)
			(end 2.750058 -2.750058)
			(stroke
				(width 0.1524)
				(type default)
			)
			(layer "F.SilkS")
		)
		(fp_line
			(start -2.750058 -1.988058)
			(end -2.750058 -0.9398)
			(stroke
				(width 0.1524)
				(type default)
			)
			(layer "F.SilkS")
		)
		(fp_line
			(start -1.988058 -2.750058)
			(end -2.750058 -1.988058)
			(stroke
				(width 0.1524)
				(type default)
			)
			(layer "F.SilkS")
		)
		(fp_line
			(start 2.750058 -2.750058)
			(end -1.988058 -2.750058)
			(stroke
				(width 0.1524)
				(type default)
			)
			(layer "F.SilkS")
		)
		(fp_line
			(start -2.750058 2.750058)
			(end 2.750058 2.750058)
			(stroke
				(width 0.1)
				(type default)
			)
			(layer "F.Fab")
		)
		(fp_line
			(start 2.750058 2.750058)
			(end 2.750058 -2.750058)
			(stroke
				(width 0.1)
				(type default)
			)
			(layer "F.Fab")
		)
		(fp_line
			(start -2.750058 -2.750058)
			(end -2.750058 2.750058)
			(stroke
				(width 0.1)
				(type default)
			)
			(layer "F.Fab")
		)
		(fp_line
			(start 2.750058 -2.750058)
			(end -2.750058 -2.750058)
			(stroke
				(width 0.1)
				(type default)
			)
			(layer "F.Fab")
		)
		(pad "1" smd rect
			(at -2.199894 0)
			(size 1.6002 3.0226)
			(layers "F.Cu" "F.Mask" "F.Paste")
			(net "PVDD11_S3_P0")
		)
		(pad "2" smd rect
			(at 2.199894 0)
			(size 1.6002 3.0226)
			(layers "F.Cu" "F.Mask" "F.Paste")
			(net "GND")
		)
	)
	(footprint ""
		(layer "F.Cu")
		(at 152.849834 -320.699892)
		(property "Reference" "R583"
			(at 0 0 0)
			(layer "F.SilkS")
			(hide yes)
			(effects
				(font
					(size 1.27 1.27)
				)
			)
		)
		(property "Value" ""
			(at 0 0 0)
			(layer "F.Fab")
			(effects
				(font
					(size 1.27 1.27)
				)
			)
		)
		(duplicate_pad_numbers_are_jumpers no)
		(fp_line
			(start -0.7874 -0.4064)
			(end 0.7874 -0.4064)
			(stroke
				(width 0.1524)
				(type default)
			)
			(layer "F.SilkS")
		)
		(fp_line
			(start -0.7874 0.4064)
			(end -0.7874 -0.4064)
			(stroke
				(width 0.1524)
				(type default)
			)
			(layer "F.SilkS")
		)
		(fp_line
			(start 0.7874 -0.4064)
			(end 0.7874 0.4064)
			(stroke
				(width 0.1524)
				(type default)
			)
			(layer "F.SilkS")
		)
		(fp_line
			(start 0.7874 0.4064)
			(end -0.7874 0.4064)
			(stroke
				(width 0.1524)
				(type default)
			)
			(layer "F.SilkS")
		)
		(fp_line
			(start -0.67945 -0.305054)
			(end -0.12065 -0.305054)
			(stroke
				(width 0.1)
				(type default)
			)
			(layer "F.Fab")
		)
		(fp_line
			(start -0.67945 0.3048)
			(end -0.67945 -0.305054)
			(stroke
				(width 0.1)
				(type default)
			)
			(layer "F.Fab")
		)
		(fp_line
			(start -0.12065 -0.305054)
			(end -0.12065 -0.2794)
			(stroke
				(width 0.1)
				(type default)
			)
			(layer "F.Fab")
		)
		(fp_line
			(start -0.12065 -0.2794)
			(end 0.12065 -0.2794)
			(stroke
				(width 0.1)
				(type default)
			)
			(layer "F.Fab")
		)
		(fp_line
			(start -0.12065 0.2794)
			(end -0.12065 0.3048)
			(stroke
				(width 0.1)
				(type default)
			)
			(layer "F.Fab")
		)
		(fp_line
			(start -0.12065 0.3048)
			(end -0.67945 0.3048)
			(stroke
				(width 0.1)
				(type default)
			)
			(layer "F.Fab")
		)
		(fp_line
			(start 0.120396 0.2794)
			(end -0.12065 0.2794)
			(stroke
				(width 0.1)
				(type default)
			)
			(layer "F.Fab")
		)
		(fp_line
			(start 0.120396 0.3048)
			(end 0.120396 0.2794)
			(stroke
				(width 0.1)
				(type default)
			)
			(layer "F.Fab")
		)
		(fp_line
			(start 0.12065 -0.3048)
			(end 0.67945 -0.3048)
			(stroke
				(width 0.1)
				(type default)
			)
			(layer "F.Fab")
		)
		(fp_line
			(start 0.12065 -0.2794)
			(end 0.12065 -0.3048)
			(stroke
				(width 0.1)
				(type default)
			)
			(layer "F.Fab")
		)
		(fp_line
			(start 0.67945 -0.3048)
			(end 0.67945 0.3048)
			(stroke
				(width 0.1)
				(type default)
			)
			(layer "F.Fab")
		)
		(fp_line
			(start 0.67945 0.3048)
			(end 0.120396 0.3048)
			(stroke
				(width 0.1)
				(type default)
			)
			(layer "F.Fab")
		)
		(pad "1" smd circle
			(at -0.40005 0)
			(size 0 0)
			(layers "F.Cu" "F.Mask" "F.Paste")
			(net "RST_CPU1_RSMRST_N")
		)
		(pad "2" smd circle
			(at 0.40005 0)
			(size 0 0)
			(layers "F.Cu" "F.Mask" "F.Paste")
			(net "PVDD18_S5_P1")
		)
	)
	(footprint ""
		(layer "F.Cu")
		(at 169.66819 -419.116256 90)
		(property "Reference" "R697"
			(at 0 0 90)
			(layer "F.SilkS")
			(hide yes)
			(effects
				(font
					(size 1.27 1.27)
				)
			)
		)
		(property "Value" ""
			(at 0 0 90)
			(layer "F.Fab")
			(effects
				(font
					(size 1.27 1.27)
				)
			)
		)
		(duplicate_pad_numbers_are_jumpers no)
		(fp_line
			(start 0.32512 -0.175006)
			(end 0.32512 0.175006)
			(stroke
				(width 0.1)
				(type default)
			)
			(layer "F.Fab")
		)
		(fp_line
			(start -0.32512 -0.175006)
			(end 0.32512 -0.175006)
			(stroke
				(width 0.1)
				(type default)
			)
			(layer "F.Fab")
		)
		(fp_line
			(start 0.32512 0.175006)
			(end -0.32512 0.175006)
			(stroke
				(width 0.1)
				(type default)
			)
			(layer "F.Fab")
		)
		(fp_line
			(start -0.32512 0.175006)
			(end -0.32512 -0.175006)
			(stroke
				(width 0.1)
				(type default)
			)
			(layer "F.Fab")
		)
		(pad "1" smd rect
			(at -0.2667 0 90)
			(size 0.3048 0.381)
			(layers "F.Cu" "F.Mask" "F.Paste")
			(net "SMB_RT_CPU1_P3_ROM_R_SCL")
		)
		(pad "2" smd rect
			(at 0.2667 0 270)
			(size 0.3048 0.381)
			(layers "F.Cu" "F.Mask" "F.Paste")
			(net "SMB_RT_CPU1_P3_ROM_SCL")
		)
	)
	(footprint ""
		(layer "F.Cu")
		(at 92.997528 -156.829252)
		(property "Reference" "PC6004"
			(at 0 0 0)
			(layer "F.SilkS")
			(hide yes)
			(effects
				(font
					(size 1.27 1.27)
				)
			)
		)
		(property "Value" ""
			(at 0 0 0)
			(layer "F.Fab")
			(effects
				(font
					(size 1.27 1.27)
				)
			)
		)
		(duplicate_pad_numbers_are_jumpers no)
		(fp_line
			(start -0.7874 -0.4064)
			(end 0.7874 -0.4064)
			(stroke
				(width 0.1524)
				(type default)
			)
			(layer "F.SilkS")
		)
		(fp_line
			(start -0.7874 0.4064)
			(end -0.7874 -0.4064)
			(stroke
				(width 0.1524)
				(type default)
			)
			(layer "F.SilkS")
		)
		(fp_line
			(start 0.7874 -0.4064)
			(end 0.7874 0.4064)
			(stroke
				(width 0.1524)
				(type default)
			)
			(layer "F.SilkS")
		)
		(fp_line
			(start 0.7874 0.4064)
			(end -0.7874 0.4064)
			(stroke
				(width 0.1524)
				(type default)
			)
			(layer "F.SilkS")
		)
		(fp_line
			(start -0.67945 -0.305054)
			(end -0.12065 -0.305054)
			(stroke
				(width 0.1)
				(type default)
			)
			(layer "F.Fab")
		)
		(fp_line
			(start -0.67945 0.3048)
			(end -0.67945 -0.305054)
			(stroke
				(width 0.1)
				(type default)
			)
			(layer "F.Fab")
		)
		(fp_line
			(start -0.12065 -0.305054)
			(end -0.12065 -0.2794)
			(stroke
				(width 0.1)
				(type default)
			)
			(layer "F.Fab")
		)
		(fp_line
			(start -0.12065 -0.2794)
			(end 0.12065 -0.2794)
			(stroke
				(width 0.1)
				(type default)
			)
			(layer "F.Fab")
		)
		(fp_line
			(start -0.12065 0.2794)
			(end -0.12065 0.3048)
			(stroke
				(width 0.1)
				(type default)
			)
			(layer "F.Fab")
		)
		(fp_line
			(start -0.12065 0.3048)
			(end -0.67945 0.3048)
			(stroke
				(width 0.1)
				(type default)
			)
			(layer "F.Fab")
		)
		(fp_line
			(start 0.120396 0.2794)
			(end -0.12065 0.2794)
			(stroke
				(width 0.1)
				(type default)
			)
			(layer "F.Fab")
		)
		(fp_line
			(start 0.120396 0.3048)
			(end 0.120396 0.2794)
			(stroke
				(width 0.1)
				(type default)
			)
			(layer "F.Fab")
		)
		(fp_line
			(start 0.12065 -0.3048)
			(end 0.67945 -0.3048)
			(stroke
				(width 0.1)
				(type default)
			)
			(layer "F.Fab")
		)
		(fp_line
			(start 0.12065 -0.2794)
			(end 0.12065 -0.3048)
			(stroke
				(width 0.1)
				(type default)
			)
			(layer "F.Fab")
		)
		(fp_line
			(start 0.67945 -0.3048)
			(end 0.67945 0.3048)
			(stroke
				(width 0.1)
				(type default)
			)
			(layer "F.Fab")
		)
		(fp_line
			(start 0.67945 0.3048)
			(end 0.120396 0.3048)
			(stroke
				(width 0.1)
				(type default)
			)
			(layer "F.Fab")
		)
		(pad "1" smd circle
			(at -0.40005 0)
			(size 0 0)
			(layers "F.Cu" "F.Mask" "F.Paste")
			(net "P12V_AUX")
		)
		(pad "2" smd circle
			(at 0.40005 0)
			(size 0 0)
			(layers "F.Cu" "F.Mask" "F.Paste")
			(net "GND")
		)
	)
	(footprint ""
		(layer "F.Cu")
		(at 10.066782 -407.262584 180)
		(property "Reference" "PC6543"
			(at 0 0 180)
			(layer "F.SilkS")
			(hide yes)
			(effects
				(font
					(size 1.27 1.27)
				)
			)
		)
		(property "Value" ""
			(at 0 0 180)
			(layer "F.Fab")
			(effects
				(font
					(size 1.27 1.27)
				)
			)
		)
		(duplicate_pad_numbers_are_jumpers no)
		(fp_line
			(start 0.7874 0.4064)
			(end -0.7874 0.4064)
			(stroke
				(width 0.1524)
				(type default)
			)
			(layer "F.SilkS")
		)
		(fp_line
			(start 0.7874 -0.4064)
			(end 0.7874 0.4064)
			(stroke
				(width 0.1524)
				(type default)
			)
			(layer "F.SilkS")
		)
		(fp_line
			(start -0.7874 0.4064)
			(end -0.7874 -0.4064)
			(stroke
				(width 0.1524)
				(type default)
			)
			(layer "F.SilkS")
		)
		(fp_line
			(start -0.7874 -0.4064)
			(end 0.7874 -0.4064)
			(stroke
				(width 0.1524)
				(type default)
			)
			(layer "F.SilkS")
		)
		(fp_line
			(start 0.67945 0.3048)
			(end 0.120396 0.3048)
			(stroke
				(width 0.1)
				(type default)
			)
			(layer "F.Fab")
		)
		(fp_line
			(start 0.67945 -0.3048)
			(end 0.67945 0.3048)
			(stroke
				(width 0.1)
				(type default)
			)
			(layer "F.Fab")
		)
		(fp_line
			(start 0.12065 -0.2794)
			(end 0.12065 -0.3048)
			(stroke
				(width 0.1)
				(type default)
			)
			(layer "F.Fab")
		)
		(fp_line
			(start 0.12065 -0.3048)
			(end 0.67945 -0.3048)
			(stroke
				(width 0.1)
				(type default)
			)
			(layer "F.Fab")
		)
		(fp_line
			(start 0.120396 0.3048)
			(end 0.120396 0.2794)
			(stroke
				(width 0.1)
				(type default)
			)
			(layer "F.Fab")
		)
		(fp_line
			(start 0.120396 0.2794)
			(end -0.12065 0.2794)
			(stroke
				(width 0.1)
				(type default)
			)
			(layer "F.Fab")
		)
		(fp_line
			(start -0.12065 0.3048)
			(end -0.67945 0.3048)
			(stroke
				(width 0.1)
				(type default)
			)
			(layer "F.Fab")
		)
		(fp_line
			(start -0.12065 0.2794)
			(end -0.12065 0.3048)
			(stroke
				(width 0.1)
				(type default)
			)
			(layer "F.Fab")
		)
		(fp_line
			(start -0.12065 -0.2794)
			(end 0.12065 -0.2794)
			(stroke
				(width 0.1)
				(type default)
			)
			(layer "F.Fab")
		)
		(fp_line
			(start -0.12065 -0.305054)
			(end -0.12065 -0.2794)
			(stroke
				(width 0.1)
				(type default)
			)
			(layer "F.Fab")
		)
		(fp_line
			(start -0.67945 0.3048)
			(end -0.67945 -0.305054)
			(stroke
				(width 0.1)
				(type default)
			)
			(layer "F.Fab")
		)
		(fp_line
			(start -0.67945 -0.305054)
			(end -0.12065 -0.305054)
			(stroke
				(width 0.1)
				(type default)
			)
			(layer "F.Fab")
		)
		(pad "1" smd circle
			(at -0.40005 0 180)
			(size 0 0)
			(layers "F.Cu" "F.Mask" "F.Paste")
			(net "P0V9_RETIMER_CPU1_VCC")
		)
		(pad "2" smd circle
			(at 0.40005 0 180)
			(size 0 0)
			(layers "F.Cu" "F.Mask" "F.Paste")
			(net "GND")
		)
	)
)
